# SCM (Grand Teton) — schematic netlist excerpt (pin names and nets, part order shuffled) for the footprints in the layout excerpt that follows; sources: Cadence DE-HDL packaged netlist, KiCad conversion of 12092022_DA0F0TMDCD0_F0T_Management_Board_D_brd_V3_OCP.brd

R445  Q_RES  33.2 1% CHIP  pkg 0402LF  page 36 : A = FM_BMC_SUSACK_N ; B = FM_BMC_SUSACK_R2_N
R71  Q_RES  33.2 1% CHIP  pkg 0402LF  page 12 : A = SMB_BMC_MM5_R_SCL ; B = SMB_BMC_MM5_SCL

(kicad_pcb
	(version 20260206)
	(generator "pcbnew")
	(generator_version "10.0")
	(general
		(thickness 1.6)
		(legacy_teardrops no)
	)
	(paper "A4")
	(title_block
		(title "12092022_DA0F0TMDCD0_F0T_Management_Board_D_brd_V3_OCP.brd")
		(comment 1 "Grand Teton / footprints 622-623 of 1440")
	)
	(layers
		(0 "F.Cu" signal "TOP")
		(4 "In1.Cu" signal "GND")
		(6 "In2.Cu" signal "IN1")
		(8 "In3.Cu" signal "GND1")
		(10 "In4.Cu" signal "IN2")
		(12 "In5.Cu" signal "VCC")
		(14 "In6.Cu" signal "VCC1")
		(16 "In7.Cu" signal "IN3")
		(18 "In8.Cu" signal "GND2")
		(20 "In9.Cu" signal "IN4")
		(22 "In10.Cu" signal "GND3")
		(2 "B.Cu" signal "BOTTOM")
		(9 "F.Adhes" user "F.Adhesive")
		(11 "B.Adhes" user "B.Adhesive")
		(13 "F.Paste" user "Package Geometry/Pastemask Top")
		(15 "B.Paste" user "Package Geometry/Pastemask Bottom")
		(5 "F.SilkS" user "Ref Des/Silkscreen Top")
		(7 "B.SilkS" user "Ref Des/Silkscreen Bottom")
		(1 "F.Mask" user "Board Geometry/Soldermask Top")
		(3 "B.Mask" user "Board Geometry/Soldermask Bottom")
		(17 "Dwgs.User" user "User.Drawings")
		(19 "Cmts.User" user "User.Comments")
		(21 "Eco1.User" user "User.Eco1")
		(23 "Eco2.User" user "User.Eco2")
		(25 "Edge.Cuts" user "Board Geometry/Outline")
		(27 "Margin" user)
		(31 "F.CrtYd" user "Package Geometry/Place Bound Top")
		(29 "B.CrtYd" user "Package Geometry/Place Bound Bottom")
		(35 "F.Fab" user "Ref Des/Assembly Top")
		(33 "B.Fab" user "Ref Des/Assembly Bottom")
	)
	(footprint ""
		(layer "F.Cu")
		(at 25.527 -102.743 -90)
		(property "Reference" "R445"
			(at 0 0 270)
			(layer "F.SilkS")
			(hide yes)
			(effects
				(font
					(size 1.27 1.27)
				)
			)
		)
		(property "Value" ""
			(at 0 0 270)
			(layer "F.Fab")
			(effects
				(font
					(size 1.27 1.27)
				)
			)
		)
		(duplicate_pad_numbers_are_jumpers no)
		(fp_line
			(start -0.7874 0.4064)
			(end -0.7874 -0.4064)
			(stroke
				(width 0.1524)
				(type default)
			)
			(layer "F.SilkS")
		)
		(fp_line
			(start 0.7874 0.4064)
			(end -0.7874 0.4064)
			(stroke
				(width 0.1524)
				(type default)
			)
			(layer "F.SilkS")
		)
		(fp_line
			(start -0.7874 -0.4064)
			(end 0.7874 -0.4064)
			(stroke
				(width 0.1524)
				(type default)
			)
			(layer "F.SilkS")
		)
		(fp_line
			(start 0.7874 -0.4064)
			(end 0.7874 0.4064)
			(stroke
				(width 0.1524)
				(type default)
			)
			(layer "F.SilkS")
		)
		(fp_line
			(start -0.67945 0.3048)
			(end -0.67945 -0.305054)
			(stroke
				(width 0.1)
				(type default)
			)
			(layer "F.Fab")
		)
		(fp_line
			(start -0.12065 0.3048)
			(end -0.67945 0.3048)
			(stroke
				(width 0.1)
				(type default)
			)
			(layer "F.Fab")
		)
		(fp_line
			(start 0.120396 0.3048)
			(end 0.120396 0.2794)
			(stroke
				(width 0.1)
				(type default)
			)
			(layer "F.Fab")
		)
		(fp_line
			(start 0.67945 0.3048)
			(end 0.120396 0.3048)
			(stroke
				(width 0.1)
				(type default)
			)
			(layer "F.Fab")
		)
		(fp_line
			(start -0.12065 0.2794)
			(end -0.12065 0.3048)
			(stroke
				(width 0.1)
				(type default)
			)
			(layer "F.Fab")
		)
		(fp_line
			(start 0.120396 0.2794)
			(end -0.12065 0.2794)
			(stroke
				(width 0.1)
				(type default)
			)
			(layer "F.Fab")
		)
		(fp_line
			(start -0.12065 -0.2794)
			(end 0.12065 -0.2794)
			(stroke
				(width 0.1)
				(type default)
			)
			(layer "F.Fab")
		)
		(fp_line
			(start 0.12065 -0.2794)
			(end 0.12065 -0.3048)
			(stroke
				(width 0.1)
				(type default)
			)
			(layer "F.Fab")
		)
		(fp_line
			(start 0.12065 -0.3048)
			(end 0.67945 -0.3048)
			(stroke
				(width 0.1)
				(type default)
			)
			(layer "F.Fab")
		)
		(fp_line
			(start 0.67945 -0.3048)
			(end 0.67945 0.3048)
			(stroke
				(width 0.1)
				(type default)
			)
			(layer "F.Fab")
		)
		(fp_line
			(start -0.67945 -0.305054)
			(end -0.12065 -0.305054)
			(stroke
				(width 0.1)
				(type default)
			)
			(layer "F.Fab")
		)
		(fp_line
			(start -0.12065 -0.305054)
			(end -0.12065 -0.2794)
			(stroke
				(width 0.1)
				(type default)
			)
			(layer "F.Fab")
		)
		(pad "1" smd circle
			(at -0.40005 0 270)
			(size 0 0)
			(layers "F.Cu" "F.Mask" "F.Paste")
			(net "FM_BMC_SUSACK_N")
		)
		(pad "2" smd circle
			(at 0.40005 0 270)
			(size 0 0)
			(layers "F.Cu" "F.Mask" "F.Paste")
			(net "FM_BMC_SUSACK_R2_N")
		)
	)
	(footprint ""
		(layer "F.Cu")
		(at 58.266584 -34.637726 -90)
		(property "Reference" "R71"
			(at 0 0 270)
			(layer "F.SilkS")
			(hide yes)
			(effects
				(font
					(size 1.27 1.27)
				)
			)
		)
		(property "Value" ""
			(at 0 0 270)
			(layer "F.Fab")
			(effects
				(font
					(size 1.27 1.27)
				)
			)
		)
		(duplicate_pad_numbers_are_jumpers no)
		(fp_line
			(start -0.7874 0.4064)
			(end -0.7874 -0.4064)
			(stroke
				(width 0.1524)
				(type default)
			)
			(layer "F.SilkS")
		)
		(fp_line
			(start 0.7874 0.4064)
			(end -0.7874 0.4064)
			(stroke
				(width 0.1524)
				(type default)
			)
			(layer "F.SilkS")
		)
		(fp_line
			(start -0.7874 -0.4064)
			(end 0.7874 -0.4064)
			(stroke
				(width 0.1524)
				(type default)
			)
			(layer "F.SilkS")
		)
		(fp_line
			(start 0.7874 -0.4064)
			(end 0.7874 0.4064)
			(stroke
				(width 0.1524)
				(type default)
			)
			(layer "F.SilkS")
		)
		(fp_line
			(start -0.67945 0.3048)
			(end -0.67945 -0.305054)
			(stroke
				(width 0.1)
				(type default)
			)
			(layer "F.Fab")
		)
		(fp_line
			(start -0.12065 0.3048)
			(end -0.67945 0.3048)
			(stroke
				(width 0.1)
				(type default)
			)
			(layer "F.Fab")
		)
		(fp_line
			(start 0.120396 0.3048)
			(end 0.120396 0.2794)
			(stroke
				(width 0.1)
				(type default)
			)
			(layer "F.Fab")
		)
		(fp_line
			(start 0.67945 0.3048)
			(end 0.120396 0.3048)
			(stroke
				(width 0.1)
				(type default)
			)
			(layer "F.Fab")
		)
		(fp_line
			(start -0.12065 0.2794)
			(end -0.12065 0.3048)
			(stroke
				(width 0.1)
				(type default)
			)
			(layer "F.Fab")
		)
		(fp_line
			(start 0.120396 0.2794)
			(end -0.12065 0.2794)
			(stroke
				(width 0.1)
				(type default)
			)
			(layer "F.Fab")
		)
		(fp_line
			(start -0.12065 -0.2794)
			(end 0.12065 -0.2794)
			(stroke
				(width 0.1)
				(type default)
			)
			(layer "F.Fab")
		)
		(fp_line
			(start 0.12065 -0.2794)
			(end 0.12065 -0.3048)
			(stroke
				(width 0.1)
				(type default)
			)
			(layer "F.Fab")
		)
		(fp_line
			(start 0.12065 -0.3048)
			(end 0.67945 -0.3048)
			(stroke
				(width 0.1)
				(type default)
			)
			(layer "F.Fab")
		)
		(fp_line
			(start 0.67945 -0.3048)
			(end 0.67945 0.3048)
			(stroke
				(width 0.1)
				(type default)
			)
			(layer "F.Fab")
		)
		(fp_line
			(start -0.67945 -0.305054)
			(end -0.12065 -0.305054)
			(stroke
				(width 0.1)
				(type default)
			)
			(layer "F.Fab")
		)
		(fp_line
			(start -0.12065 -0.305054)
			(end -0.12065 -0.2794)
			(stroke
				(width 0.1)
				(type default)
			)
			(layer "F.Fab")
		)
		(pad "1" smd circle
			(at -0.40005 0 270)
			(size 0 0)
			(layers "F.Cu" "F.Mask" "F.Paste")
			(net "SMB_BMC_MM5_R_SCL")
		)
		(pad "2" smd circle
			(at 0.40005 0 270)
			(size 0 0)
			(layers "F.Cu" "F.Mask" "F.Paste")
			(net "SMB_BMC_MM5_SCL")
		)
	)
)
